(kicad_pcb
	(version 20260206)
	(generator "pcbnew")
	(generator_version "10.0")
	(general
		(thickness 1.6)
		(legacy_teardrops no)
	)
	(paper "A4")
	(title_block
		(title "panther-plus-userver — 13130-1b_20150205.brd")
		(comment 1 "Honey Badger (Wiwynn) / footprint 624 of 1509 (DIMM4), pads 156-162 of 210")
	)
	(layers
		(0 "F.Cu" signal "TOP")
		(4 "In1.Cu" signal "L2")
		(6 "In2.Cu" signal "L3")
		(8 "In3.Cu" signal "L4")
		(10 "In4.Cu" signal "L5")
		(12 "In5.Cu" signal "L6")
		(14 "In6.Cu" signal "L7")
		(16 "In7.Cu" signal "L8")
		(18 "In8.Cu" signal "L9")
		(20 "In9.Cu" signal "L10")
		(22 "In10.Cu" signal "L11")
		(2 "B.Cu" signal "BOTTOM")
		(9 "F.Adhes" user "F.Adhesive")
		(11 "B.Adhes" user "B.Adhesive")
		(13 "F.Paste" user "Package Geometry/Pastemask Top")
		(15 "B.Paste" user "Package Geometry/Pastemask Bottom")
		(5 "F.SilkS" user "Ref Des/Silkscreen Top")
		(7 "B.SilkS" user "Ref Des/Silkscreen Bottom")
		(1 "F.Mask" user "Board Geometry/Soldermask Top")
		(3 "B.Mask" user "Board Geometry/Soldermask Bottom")
		(17 "Dwgs.User" user "User.Drawings")
		(19 "Cmts.User" user "User.Comments")
		(21 "Eco1.User" user "User.Eco1")
		(23 "Eco2.User" user "User.Eco2")
		(25 "Edge.Cuts" user "Board Geometry/Outline")
		(27 "Margin" user)
		(31 "F.CrtYd" user "Package Geometry/Place Bound Top")
		(29 "B.CrtYd" user "Package Geometry/Place Bound Bottom")
		(35 "F.Fab" user "Ref Des/Assembly Top")
		(33 "B.Fab" user "Ref Des/Assembly Bottom")
	)
	(footprint ""
		(layer "F.Cu")
		(at 159.999934 -5.790692)
		(property "Reference" "DIMM4"
			(at 0 0 0)
			(layer "F.SilkS")
			(hide yes)
			(effects
				(font
					(size 1.27 1.27)
				)
			)
		)
		(property "Value" "DDR3-204P-174-COLAY-1-GP"
			(at -40.682164 -17.468088 0)
			(unlocked yes)
			(layer "F.Fab")
			(hide yes)
			(effects
				(font
					(size 1.016 1.016)
					(thickness 0.1524)
				)
			)
		)
		(property "Device Type" "AS0A626-H8SN-7H-COLAY-1"
			(at -40.682164 -18.992088 0)
			(unlocked yes)
			(layer "F.Fab")
			(hide yes)
			(effects
				(font
					(size 1.016 1.016)
					(thickness 0.1524)
				)
			)
		)
		(duplicate_pad_numbers_are_jumpers no)
		(pad "154" smd custom
			(at 16.649954 -4.106672)
			(size 0.1143 0.1143)
			(layers "F.Cu" "F.Mask" "F.Paste")
			(net "M_B_DQS_DN5")
			(options
				(clearance outline)
				(anchor circle)
			)
			(primitives
				(gr_poly
					(pts
						(xy 0 0.9017) (xy -0.03175 0.89916) (xy -0.0635 0.889) (xy -0.09144 0.87376) (xy -0.11684 0.85344)
						(xy -0.13716 0.82804) (xy -0.1524 0.8001) (xy -0.16256 0.76835) (xy -0.1651 0.7366) (xy -0.1651 0.44958)
						(xy -0.17272 0.44196) (xy -0.19812 0.4064) (xy -0.2032 0.39624) (xy -0.20701 0.38735) (xy -0.21209 0.37719)
						(xy -0.2159 0.36703) (xy -0.21844 0.35687) (xy -0.22225 0.34544) (xy -0.22352 0.33528) (xy -0.22606 0.32512)
						(xy -0.22733 0.31369) (xy -0.22733 0.30353) (xy -0.2286 0.2921) (xy -0.22733 0.28067) (xy -0.22733 0.27051)
						(xy -0.22606 0.25908) (xy -0.22352 0.24892) (xy -0.22225 0.23876) (xy -0.21844 0.22733) (xy -0.2159 0.21717)
						(xy -0.21209 0.20701) (xy -0.20701 0.19685) (xy -0.2032 0.18796) (xy -0.19812 0.1778) (xy -0.17272 0.14224)
						(xy -0.1651 0.13462) (xy -0.1651 -0.7366) (xy -0.16256 -0.76835) (xy -0.1524 -0.8001) (xy -0.13716 -0.82804)
						(xy -0.11684 -0.85344) (xy -0.09144 -0.87376) (xy -0.0635 -0.889) (xy -0.03175 -0.89916) (xy 0 -0.9017)
						(xy 0.03175 -0.89916) (xy 0.0635 -0.889) (xy 0.09144 -0.87376) (xy 0.11684 -0.85344) (xy 0.13716 -0.82804)
						(xy 0.1524 -0.8001) (xy 0.16256 -0.76835) (xy 0.1651 -0.7366) (xy 0.1651 0.13462) (xy 0.17272 0.14224)
						(xy 0.19812 0.1778) (xy 0.2032 0.18796) (xy 0.20701 0.19685) (xy 0.21209 0.20701) (xy 0.2159 0.21717)
						(xy 0.21844 0.22733) (xy 0.22225 0.23876) (xy 0.22352 0.24892) (xy 0.22606 0.25908) (xy 0.22733 0.27051)
						(xy 0.22733 0.28067) (xy 0.2286 0.2921) (xy 0.22733 0.30353) (xy 0.22733 0.31369) (xy 0.22606 0.32512)
						(xy 0.22352 0.33528) (xy 0.22225 0.34544) (xy 0.21844 0.35687) (xy 0.2159 0.36703) (xy 0.21209 0.37719)
						(xy 0.20701 0.38735) (xy 0.2032 0.39624) (xy 0.19812 0.4064) (xy 0.17272 0.44196) (xy 0.1651 0.44958)
						(xy 0.1651 0.7366) (xy 0.16256 0.76835) (xy 0.1524 0.8001) (xy 0.13716 0.82804) (xy 0.11684 0.85344)
						(xy 0.09144 0.87376) (xy 0.0635 0.889) (xy 0.03175 0.89916)
					)
					(width 0)
					(fill yes)
				)
			)
		)
		(pad "155" smd custom
			(at 16.949928 4.106672)
			(size 0.1143 0.1143)
			(layers "F.Cu" "F.Mask" "F.Paste")
			(net "GND")
			(options
				(clearance outline)
				(anchor circle)
			)
			(primitives
				(gr_poly
					(pts
						(xy 0 0.9017) (xy -0.03175 0.89916) (xy -0.0635 0.889) (xy -0.09144 0.87376) (xy -0.11684 0.85344)
						(xy -0.13716 0.82804) (xy -0.1524 0.8001) (xy -0.16256 0.76835) (xy -0.1651 0.7366) (xy -0.1651 0.11938)
						(xy -0.17272 0.11176) (xy -0.19812 0.0762) (xy -0.2032 0.06604) (xy -0.20701 0.05715) (xy -0.21209 0.04699)
						(xy -0.2159 0.03683) (xy -0.21844 0.02667) (xy -0.22225 0.01524) (xy -0.22352 0.00508) (xy -0.22606 -0.00508)
						(xy -0.22733 -0.01651) (xy -0.22733 -0.02667) (xy -0.2286 -0.0381) (xy -0.22733 -0.04953) (xy -0.22733 -0.05969)
						(xy -0.22606 -0.07112) (xy -0.22352 -0.08128) (xy -0.22225 -0.09144) (xy -0.21844 -0.10287) (xy -0.2159 -0.11303)
						(xy -0.21209 -0.12319) (xy -0.20701 -0.13335) (xy -0.2032 -0.14224) (xy -0.19812 -0.1524) (xy -0.17272 -0.18796)
						(xy -0.1651 -0.19558) (xy -0.1651 -0.7366) (xy -0.16256 -0.76835) (xy -0.1524 -0.8001) (xy -0.13716 -0.82804)
						(xy -0.11684 -0.85344) (xy -0.09144 -0.87376) (xy -0.0635 -0.889) (xy -0.03175 -0.89916) (xy 0 -0.9017)
						(xy 0.03175 -0.89916) (xy 0.0635 -0.889) (xy 0.09144 -0.87376) (xy 0.11684 -0.85344) (xy 0.13716 -0.82804)
						(xy 0.1524 -0.8001) (xy 0.16256 -0.76835) (xy 0.1651 -0.7366) (xy 0.1651 -0.19685) (xy 0.17272 -0.18923)
						(xy 0.17907 -0.18034) (xy 0.18669 -0.17145) (xy 0.19177 -0.16256) (xy 0.19812 -0.15367) (xy 0.20828 -0.13335)
						(xy 0.21971 -0.10287) (xy 0.22225 -0.09271) (xy 0.22479 -0.08128) (xy 0.22606 -0.07112) (xy 0.2286 -0.05969)
						(xy 0.2286 -0.01651) (xy 0.22606 -0.00508) (xy 0.22479 0.00508) (xy 0.22225 0.01651) (xy 0.21971 0.02667)
						(xy 0.20828 0.05715) (xy 0.19812 0.07747) (xy 0.19177 0.08636) (xy 0.18669 0.09525) (xy 0.17907 0.10414)
						(xy 0.17272 0.11303) (xy 0.1651 0.12065) (xy 0.1651 0.7366) (xy 0.16256 0.76835) (xy 0.1524 0.8001)
						(xy 0.13716 0.82804) (xy 0.11684 0.85344) (xy 0.09144 0.87376) (xy 0.0635 0.889) (xy 0.03175 0.89916)
					)
					(width 0)
					(fill yes)
				)
			)
		)
		(pad "156" smd custom
			(at 17.249902 -4.106672)
			(size 0.1143 0.1143)
			(layers "F.Cu" "F.Mask" "F.Paste")
			(net "M_B_DQS_DP5")
			(options
				(clearance outline)
				(anchor circle)
			)
			(primitives
				(gr_poly
					(pts
						(xy 0 0.9017) (xy -0.03175 0.89916) (xy -0.0635 0.889) (xy -0.09144 0.87376) (xy -0.11684 0.85344)
						(xy -0.13716 0.82804) (xy -0.1524 0.8001) (xy -0.16256 0.76835) (xy -0.1651 0.7366) (xy -0.1651 0.19685)
						(xy -0.17272 0.18923) (xy -0.17907 0.18034) (xy -0.18669 0.17145) (xy -0.19177 0.16256) (xy -0.19812 0.15367)
						(xy -0.20828 0.13335) (xy -0.21971 0.10287) (xy -0.22225 0.09271) (xy -0.22479 0.08128) (xy -0.22606 0.07112)
						(xy -0.2286 0.05969) (xy -0.2286 0.01651) (xy -0.22606 0.00508) (xy -0.22479 -0.00508) (xy -0.22225 -0.01651)
						(xy -0.21971 -0.02667) (xy -0.20828 -0.05715) (xy -0.19812 -0.07747) (xy -0.19177 -0.08636) (xy -0.18669 -0.09525)
						(xy -0.17907 -0.10414) (xy -0.17272 -0.11303) (xy -0.1651 -0.12065) (xy -0.1651 -0.7366) (xy -0.16256 -0.76835)
						(xy -0.1524 -0.8001) (xy -0.13716 -0.82804) (xy -0.11684 -0.85344) (xy -0.09144 -0.87376) (xy -0.0635 -0.889)
						(xy -0.03175 -0.89916) (xy 0 -0.9017) (xy 0.03175 -0.89916) (xy 0.0635 -0.889) (xy 0.09144 -0.87376)
						(xy 0.11684 -0.85344) (xy 0.13716 -0.82804) (xy 0.1524 -0.8001) (xy 0.16256 -0.76835) (xy 0.1651 -0.7366)
						(xy 0.1651 -0.11938) (xy 0.17272 -0.11176) (xy 0.19812 -0.0762) (xy 0.2032 -0.06604) (xy 0.20701 -0.05715)
						(xy 0.21209 -0.04699) (xy 0.2159 -0.03683) (xy 0.21844 -0.02667) (xy 0.22225 -0.01524) (xy 0.22352 -0.00508)
						(xy 0.22606 0.00508) (xy 0.22733 0.01651) (xy 0.22733 0.02667) (xy 0.2286 0.0381) (xy 0.22733 0.04953)
						(xy 0.22733 0.05969) (xy 0.22606 0.07112) (xy 0.22352 0.08128) (xy 0.22225 0.09144) (xy 0.21844 0.10287)
						(xy 0.2159 0.11303) (xy 0.21209 0.12319) (xy 0.20701 0.13335) (xy 0.2032 0.14224) (xy 0.19812 0.1524)
						(xy 0.17272 0.18796) (xy 0.1651 0.19558) (xy 0.1651 0.7366) (xy 0.16256 0.76835) (xy 0.1524 0.8001)
						(xy 0.13716 0.82804) (xy 0.11684 0.85344) (xy 0.09144 0.87376) (xy 0.0635 0.889) (xy 0.03175 0.89916)
					)
					(width 0)
					(fill yes)
				)
			)
		)
		(pad "157" smd custom
			(at 17.549876 4.106672)
			(size 0.1143 0.1143)
			(layers "F.Cu" "F.Mask" "F.Paste")
			(net "GND")
			(options
				(clearance outline)
				(anchor circle)
			)
			(primitives
				(gr_poly
					(pts
						(xy 0 0.9017) (xy -0.03175 0.89916) (xy -0.0635 0.889) (xy -0.09144 0.87376) (xy -0.11684 0.85344)
						(xy -0.13716 0.82804) (xy -0.1524 0.8001) (xy -0.16256 0.76835) (xy -0.1651 0.7366) (xy -0.1651 -0.13462)
						(xy -0.17272 -0.14224) (xy -0.19812 -0.1778) (xy -0.2032 -0.18796) (xy -0.20701 -0.19685) (xy -0.21209 -0.20701)
						(xy -0.2159 -0.21717) (xy -0.21844 -0.22733) (xy -0.22225 -0.23876) (xy -0.22352 -0.24892) (xy -0.22606 -0.25908)
						(xy -0.22733 -0.27051) (xy -0.22733 -0.28067) (xy -0.2286 -0.2921) (xy -0.22733 -0.30353) (xy -0.22733 -0.31369)
						(xy -0.22606 -0.32512) (xy -0.22352 -0.33528) (xy -0.22225 -0.34544) (xy -0.21844 -0.35687) (xy -0.2159 -0.36703)
						(xy -0.21209 -0.37719) (xy -0.20701 -0.38735) (xy -0.2032 -0.39624) (xy -0.19812 -0.4064) (xy -0.17272 -0.44196)
						(xy -0.1651 -0.44958) (xy -0.1651 -0.7366) (xy -0.16256 -0.76835) (xy -0.1524 -0.8001) (xy -0.13716 -0.82804)
						(xy -0.11684 -0.85344) (xy -0.09144 -0.87376) (xy -0.0635 -0.889) (xy -0.03175 -0.89916) (xy 0 -0.9017)
						(xy 0.03175 -0.89916) (xy 0.0635 -0.889) (xy 0.09144 -0.87376) (xy 0.11684 -0.85344) (xy 0.13716 -0.82804)
						(xy 0.1524 -0.8001) (xy 0.16256 -0.76835) (xy 0.1651 -0.7366) (xy 0.1651 -0.44958) (xy 0.17272 -0.44196)
						(xy 0.19812 -0.4064) (xy 0.2032 -0.39624) (xy 0.20701 -0.38735) (xy 0.21209 -0.37719) (xy 0.2159 -0.36703)
						(xy 0.21844 -0.35687) (xy 0.22225 -0.34544) (xy 0.22352 -0.33528) (xy 0.22606 -0.32512) (xy 0.22733 -0.31369)
						(xy 0.22733 -0.30353) (xy 0.2286 -0.2921) (xy 0.22733 -0.28067) (xy 0.22733 -0.27051) (xy 0.22606 -0.25908)
						(xy 0.22352 -0.24892) (xy 0.22225 -0.23876) (xy 0.21844 -0.22733) (xy 0.2159 -0.21717) (xy 0.21209 -0.20701)
						(xy 0.20701 -0.19685) (xy 0.2032 -0.18796) (xy 0.19812 -0.1778) (xy 0.17272 -0.14224) (xy 0.1651 -0.13462)
						(xy 0.1651 0.7366) (xy 0.16256 0.76835) (xy 0.1524 0.8001) (xy 0.13716 0.82804) (xy 0.11684 0.85344)
						(xy 0.09144 0.87376) (xy 0.0635 0.889) (xy 0.03175 0.89916)
					)
					(width 0)
					(fill yes)
				)
			)
		)
		(pad "158" smd custom
			(at 17.850104 -4.106672)
			(size 0.1143 0.1143)
			(layers "F.Cu" "F.Mask" "F.Paste")
			(net "GND")
			(options
				(clearance outline)
				(anchor circle)
			)
			(primitives
				(gr_poly
					(pts
						(xy 0 0.9017) (xy -0.03175 0.89916) (xy -0.0635 0.889) (xy -0.09144 0.87376) (xy -0.11684 0.85344)
						(xy -0.13716 0.82804) (xy -0.1524 0.8001) (xy -0.16256 0.76835) (xy -0.1651 0.7366) (xy -0.1651 0.44958)
						(xy -0.17272 0.44196) (xy -0.19812 0.4064) (xy -0.2032 0.39624) (xy -0.20701 0.38735) (xy -0.21209 0.37719)
						(xy -0.2159 0.36703) (xy -0.21844 0.35687) (xy -0.22225 0.34544) (xy -0.22352 0.33528) (xy -0.22606 0.32512)
						(xy -0.22733 0.31369) (xy -0.22733 0.30353) (xy -0.2286 0.2921) (xy -0.22733 0.28067) (xy -0.22733 0.27051)
						(xy -0.22606 0.25908) (xy -0.22352 0.24892) (xy -0.22225 0.23876) (xy -0.21844 0.22733) (xy -0.2159 0.21717)
						(xy -0.21209 0.20701) (xy -0.20701 0.19685) (xy -0.2032 0.18796) (xy -0.19812 0.1778) (xy -0.17272 0.14224)
						(xy -0.1651 0.13462) (xy -0.1651 -0.7366) (xy -0.16256 -0.76835) (xy -0.1524 -0.8001) (xy -0.13716 -0.82804)
						(xy -0.11684 -0.85344) (xy -0.09144 -0.87376) (xy -0.0635 -0.889) (xy -0.03175 -0.89916) (xy 0 -0.9017)
						(xy 0.03175 -0.89916) (xy 0.0635 -0.889) (xy 0.09144 -0.87376) (xy 0.11684 -0.85344) (xy 0.13716 -0.82804)
						(xy 0.1524 -0.8001) (xy 0.16256 -0.76835) (xy 0.1651 -0.7366) (xy 0.1651 0.13462) (xy 0.17272 0.14224)
						(xy 0.19812 0.1778) (xy 0.2032 0.18796) (xy 0.20701 0.19685) (xy 0.21209 0.20701) (xy 0.2159 0.21717)
						(xy 0.21844 0.22733) (xy 0.22225 0.23876) (xy 0.22352 0.24892) (xy 0.22606 0.25908) (xy 0.22733 0.27051)
						(xy 0.22733 0.28067) (xy 0.2286 0.2921) (xy 0.22733 0.30353) (xy 0.22733 0.31369) (xy 0.22606 0.32512)
						(xy 0.22352 0.33528) (xy 0.22225 0.34544) (xy 0.21844 0.35687) (xy 0.2159 0.36703) (xy 0.21209 0.37719)
						(xy 0.20701 0.38735) (xy 0.2032 0.39624) (xy 0.19812 0.4064) (xy 0.17272 0.44196) (xy 0.1651 0.44958)
						(xy 0.1651 0.7366) (xy 0.16256 0.76835) (xy 0.1524 0.8001) (xy 0.13716 0.82804) (xy 0.11684 0.85344)
						(xy 0.09144 0.87376) (xy 0.0635 0.889) (xy 0.03175 0.89916)
					)
					(width 0)
					(fill yes)
				)
			)
		)
		(pad "159" smd custom
			(at 18.150078 4.106672)
			(size 0.1143 0.1143)
			(layers "F.Cu" "F.Mask" "F.Paste")
			(net "M_B_DQ46")
			(options
				(clearance outline)
				(anchor circle)
			)
			(primitives
				(gr_poly
					(pts
						(xy 0 0.9017) (xy -0.03175 0.89916) (xy -0.0635 0.889) (xy -0.09144 0.87376) (xy -0.11684 0.85344)
						(xy -0.13716 0.82804) (xy -0.1524 0.8001) (xy -0.16256 0.76835) (xy -0.1651 0.7366) (xy -0.1651 0.11938)
						(xy -0.17272 0.11176) (xy -0.19812 0.0762) (xy -0.2032 0.06604) (xy -0.20701 0.05715) (xy -0.21209 0.04699)
						(xy -0.2159 0.03683) (xy -0.21844 0.02667) (xy -0.22225 0.01524) (xy -0.22352 0.00508) (xy -0.22606 -0.00508)
						(xy -0.22733 -0.01651) (xy -0.22733 -0.02667) (xy -0.2286 -0.0381) (xy -0.22733 -0.04953) (xy -0.22733 -0.05969)
						(xy -0.22606 -0.07112) (xy -0.22352 -0.08128) (xy -0.22225 -0.09144) (xy -0.21844 -0.10287) (xy -0.2159 -0.11303)
						(xy -0.21209 -0.12319) (xy -0.20701 -0.13335) (xy -0.2032 -0.14224) (xy -0.19812 -0.1524) (xy -0.17272 -0.18796)
						(xy -0.1651 -0.19558) (xy -0.1651 -0.7366) (xy -0.16256 -0.76835) (xy -0.1524 -0.8001) (xy -0.13716 -0.82804)
						(xy -0.11684 -0.85344) (xy -0.09144 -0.87376) (xy -0.0635 -0.889) (xy -0.03175 -0.89916) (xy 0 -0.9017)
						(xy 0.03175 -0.89916) (xy 0.0635 -0.889) (xy 0.09144 -0.87376) (xy 0.11684 -0.85344) (xy 0.13716 -0.82804)
						(xy 0.1524 -0.8001) (xy 0.16256 -0.76835) (xy 0.1651 -0.7366) (xy 0.1651 -0.19685) (xy 0.17272 -0.18923)
						(xy 0.17907 -0.18034) (xy 0.18669 -0.17145) (xy 0.19177 -0.16256) (xy 0.19812 -0.15367) (xy 0.20828 -0.13335)
						(xy 0.21971 -0.10287) (xy 0.22225 -0.09271) (xy 0.22479 -0.08128) (xy 0.22606 -0.07112) (xy 0.2286 -0.05969)
						(xy 0.2286 -0.01651) (xy 0.22606 -0.00508) (xy 0.22479 0.00508) (xy 0.22225 0.01651) (xy 0.21971 0.02667)
						(xy 0.20828 0.05715) (xy 0.19812 0.07747) (xy 0.19177 0.08636) (xy 0.18669 0.09525) (xy 0.17907 0.10414)
						(xy 0.17272 0.11303) (xy 0.1651 0.12065) (xy 0.1651 0.7366) (xy 0.16256 0.76835) (xy 0.1524 0.8001)
						(xy 0.13716 0.82804) (xy 0.11684 0.85344) (xy 0.09144 0.87376) (xy 0.0635 0.889) (xy 0.03175 0.89916)
					)
					(width 0)
					(fill yes)
				)
			)
		)
		(pad "160" smd custom
			(at 18.450052 -4.106672)
			(size 0.1143 0.1143)
			(layers "F.Cu" "F.Mask" "F.Paste")
			(net "M_B_DQ42")
			(options
				(clearance outline)
				(anchor circle)
			)
			(primitives
				(gr_poly
					(pts
						(xy 0 0.9017) (xy -0.03175 0.89916) (xy -0.0635 0.889) (xy -0.09144 0.87376) (xy -0.11684 0.85344)
						(xy -0.13716 0.82804) (xy -0.1524 0.8001) (xy -0.16256 0.76835) (xy -0.1651 0.7366) (xy -0.1651 0.19685)
						(xy -0.17272 0.18923) (xy -0.17907 0.18034) (xy -0.18669 0.17145) (xy -0.19177 0.16256) (xy -0.19812 0.15367)
						(xy -0.20828 0.13335) (xy -0.21971 0.10287) (xy -0.22225 0.09271) (xy -0.22479 0.08128) (xy -0.22606 0.07112)
						(xy -0.2286 0.05969) (xy -0.2286 0.01651) (xy -0.22606 0.00508) (xy -0.22479 -0.00508) (xy -0.22225 -0.01651)
						(xy -0.21971 -0.02667) (xy -0.20828 -0.05715) (xy -0.19812 -0.07747) (xy -0.19177 -0.08636) (xy -0.18669 -0.09525)
						(xy -0.17907 -0.10414) (xy -0.17272 -0.11303) (xy -0.1651 -0.12065) (xy -0.1651 -0.7366) (xy -0.16256 -0.76835)
						(xy -0.1524 -0.8001) (xy -0.13716 -0.82804) (xy -0.11684 -0.85344) (xy -0.09144 -0.87376) (xy -0.0635 -0.889)
						(xy -0.03175 -0.89916) (xy 0 -0.9017) (xy 0.03175 -0.89916) (xy 0.0635 -0.889) (xy 0.09144 -0.87376)
						(xy 0.11684 -0.85344) (xy 0.13716 -0.82804) (xy 0.1524 -0.8001) (xy 0.16256 -0.76835) (xy 0.1651 -0.7366)
						(xy 0.1651 -0.11938) (xy 0.17272 -0.11176) (xy 0.19812 -0.0762) (xy 0.2032 -0.06604) (xy 0.20701 -0.05715)
						(xy 0.21209 -0.04699) (xy 0.2159 -0.03683) (xy 0.21844 -0.02667) (xy 0.22225 -0.01524) (xy 0.22352 -0.00508)
						(xy 0.22606 0.00508) (xy 0.22733 0.01651) (xy 0.22733 0.02667) (xy 0.2286 0.0381) (xy 0.22733 0.04953)
						(xy 0.22733 0.05969) (xy 0.22606 0.07112) (xy 0.22352 0.08128) (xy 0.22225 0.09144) (xy 0.21844 0.10287)
						(xy 0.2159 0.11303) (xy 0.21209 0.12319) (xy 0.20701 0.13335) (xy 0.2032 0.14224) (xy 0.19812 0.1524)
						(xy 0.17272 0.18796) (xy 0.1651 0.19558) (xy 0.1651 0.7366) (xy 0.16256 0.76835) (xy 0.1524 0.8001)
						(xy 0.13716 0.82804) (xy 0.11684 0.85344) (xy 0.09144 0.87376) (xy 0.0635 0.889) (xy 0.03175 0.89916)
					)
					(width 0)
					(fill yes)
				)
			)
		)
	)
)
